# TIMECARD (Time Appliance Project (Time Card)) — schematic netlist excerpt (pin names and nets, part order shuffled) for the footprints in the layout excerpt that follows; sources: Cadence DE-HDL packaged netlist, KiCad conversion of R4006-B0001-02_R01.brd

R101  RESISTOR  1KOHM 1%  pkg SMC_0402R_H016  page 21 : \1\ = XP5R0V_USB_CONN ; \2\ = XP5R0V_USB_CONN_DET
R326  RESISTOR  4.7KOHM 1%  pkg SMC_0402R_H016  page 25 : \1\ = SG ; \2\ = FPGA_IO_6

(kicad_pcb
	(version 20260206)
	(generator "pcbnew")
	(generator_version "10.0")
	(general
		(thickness 1.6)
		(legacy_teardrops no)
	)
	(paper "A4")
	(title_block
		(title "timecard-production-celestica-r4006 — R4006-B0001-02_R01.brd")
		(comment 1 "Time Appliance Project (Time Card) / footprints 972-973 of 1113")
	)
	(layers
		(0 "F.Cu" signal "TOP")
		(4 "In1.Cu" signal "L02_GND1")
		(6 "In2.Cu" signal "L03_SIG1")
		(8 "In3.Cu" signal "L04_GND2")
		(10 "In4.Cu" signal "L05_VCC1")
		(12 "In5.Cu" signal "L06_VCC2")
		(14 "In6.Cu" signal "L07_GND3")
		(16 "In7.Cu" signal "L08_SIG2")
		(18 "In8.Cu" signal "L09_GND4")
		(2 "B.Cu" signal "BOTTOM")
		(9 "F.Adhes" user "F.Adhesive")
		(11 "B.Adhes" user "B.Adhesive")
		(13 "F.Paste" user "Package Geometry/Pastemask Top")
		(15 "B.Paste" user "Package Geometry/Pastemask Bottom")
		(5 "F.SilkS" user "Ref Des/Silkscreen Top")
		(7 "B.SilkS" user "Ref Des/Silkscreen Bottom")
		(1 "F.Mask" user "Board Geometry/Soldermask Top")
		(3 "B.Mask" user "Board Geometry/Soldermask Bottom")
		(17 "Dwgs.User" user "User.Drawings")
		(19 "Cmts.User" user "User.Comments")
		(21 "Eco1.User" user "User.Eco1")
		(23 "Eco2.User" user "User.Eco2")
		(25 "Edge.Cuts" user "Board Geometry/Outline")
		(27 "Margin" user)
		(31 "F.CrtYd" user "Package Geometry/Place Bound Top")
		(29 "B.CrtYd" user "Package Geometry/Place Bound Bottom")
		(35 "F.Fab" user "Ref Des/Assembly Top")
		(33 "B.Fab" user "Ref Des/Assembly Bottom")
	)
	(footprint ""
		(layer "B.Cu")
		(at 106.9086 -64.2874 90)
		(property "Reference" "R326"
			(at 3.5306 -0.14097 270)
			(unlocked yes)
			(layer "B.SilkS")
			(effects
				(font
					(size 0.7874 0.5842)
					(thickness 0.1524)
				)
				(justify mirror)
			)
		)
		(property "Value" "VAL*"
			(at -0.02032 2.13233 90)
			(unlocked yes)
			(layer "B.Fab")
			(hide yes)
			(effects
				(font
					(size 0.7874 0.5842)
					(thickness 0.1524)
				)
				(justify mirror)
			)
		)
		(property "Tolerance" "TOL*"
			(at -0.044704 3.05435 90)
			(unlocked yes)
			(layer "Cmts.User")
			(hide yes)
			(effects
				(font
					(size 0.7874 0.5842)
					(thickness 0.1524)
				)
				(justify mirror)
			)
		)
		(property "User Part Number" "PARTNUM*"
			(at -0.02032 4.024884 90)
			(unlocked yes)
			(layer "Cmts.User")
			(hide yes)
			(effects
				(font
					(size 0.7874 0.5842)
					(thickness 0.1524)
				)
				(justify mirror)
			)
		)
		(property "Device Type" "RESISTOR-G155-14701-01,4.7KOHMA"
			(at -0.008382 1.210564 90)
			(unlocked yes)
			(layer "B.Fab")
			(hide yes)
			(effects
				(font
					(size 0.7874 0.5842)
					(thickness 0.1524)
				)
				(justify mirror)
			)
		)
		(duplicate_pad_numbers_are_jumpers no)
		(fp_line
			(start 1.143 -0.5588)
			(end 1.143 0.5588)
			(stroke
				(width 0.1)
				(type default)
			)
			(layer "B.SilkS")
		)
		(fp_line
			(start -1.143 -0.5588)
			(end 1.143 -0.5588)
			(stroke
				(width 0.1)
				(type default)
			)
			(layer "B.SilkS")
		)
		(fp_line
			(start 1.143 0.5588)
			(end -1.143 0.5588)
			(stroke
				(width 0.1)
				(type default)
			)
			(layer "B.SilkS")
		)
		(fp_line
			(start -1.143 0.5588)
			(end -1.143 -0.5588)
			(stroke
				(width 0.1)
				(type default)
			)
			(layer "B.SilkS")
		)
		(fp_poly
			(pts
				(xy 1.143 0.5588) (xy -1.143 0.5588) (xy -1.143 -0.5588) (xy 1.143 -0.5588)
			)
			(stroke
				(width 0)
				(type default)
			)
			(fill no)
			(layer "B.CrtYd")
		)
		(fp_line
			(start 0.508 -0.3048)
			(end 0.508 0.3048)
			(stroke
				(width 0.1)
				(type default)
			)
			(layer "B.Fab")
		)
		(fp_line
			(start -0.508 -0.3048)
			(end 0.508 -0.3048)
			(stroke
				(width 0.1)
				(type default)
			)
			(layer "B.Fab")
		)
		(fp_line
			(start 0.508 0.3048)
			(end -0.508 0.3048)
			(stroke
				(width 0.1)
				(type default)
			)
			(layer "B.Fab")
		)
		(fp_line
			(start -0.508 0.3048)
			(end -0.508 -0.3048)
			(stroke
				(width 0.1)
				(type default)
			)
			(layer "B.Fab")
		)
		(pad "1" smd rect
			(at 0.5334 0 270)
			(size 0.7112 0.6096)
			(layers "B.Cu" "B.Mask" "B.Paste")
			(net "SG")
		)
		(pad "2" smd rect
			(at -0.5334 0 270)
			(size 0.7112 0.6096)
			(layers "B.Cu" "B.Mask" "B.Paste")
			(net "FPGA_IO_6")
		)
		(zone
			(layer "B.Cu")
			(hatch none 0.5)
			(connect_pads
				(clearance 0)
			)
			(min_thickness 0.25)
			(keepout
				(tracks not_allowed)
				(vias allowed)
				(pads allowed)
				(copperpour not_allowed)
				(footprints allowed)
			)
			(placement
				(enabled no)
				(sheetname "")
			)
			(fill
				(thermal_gap 0.5)
				(thermal_bridge_width 0.5)
				(island_removal_mode 0)
			)
			(polygon
				(pts
					(xy 107.2134 -64.3636) (xy 106.6038 -64.3636) (xy 106.6038 -64.2112) (xy 107.2134 -64.2112)
				)
			)
		)
		(zone
			(layer "B.Cu")
			(hatch none 0.5)
			(connect_pads
				(clearance 0)
			)
			(min_thickness 0.25)
			(keepout
				(tracks allowed)
				(vias not_allowed)
				(pads allowed)
				(copperpour not_allowed)
				(footprints allowed)
			)
			(placement
				(enabled no)
				(sheetname "")
			)
			(fill
				(thermal_gap 0.5)
				(thermal_bridge_width 0.5)
				(island_removal_mode 0)
			)
			(polygon
				(pts
					(xy 107.2134 -64.3636) (xy 106.6038 -64.3636) (xy 106.6038 -64.2112) (xy 107.2134 -64.2112)
				)
			)
		)
	)
	(footprint ""
		(layer "B.Cu")
		(at 160.02 -50.513996 90)
		(property "Reference" "R101"
			(at -7.874 1.35763 270)
			(unlocked yes)
			(layer "B.SilkS")
			(effects
				(font
					(size 0.7874 0.5842)
					(thickness 0.1524)
				)
				(justify mirror)
			)
		)
		(property "Value" "VAL*"
			(at -0.02032 2.13233 90)
			(unlocked yes)
			(layer "B.Fab")
			(hide yes)
			(effects
				(font
					(size 0.7874 0.5842)
					(thickness 0.1524)
				)
				(justify mirror)
			)
		)
		(property "Tolerance" "TOL*"
			(at -0.044704 3.05435 90)
			(unlocked yes)
			(layer "Cmts.User")
			(hide yes)
			(effects
				(font
					(size 0.7874 0.5842)
					(thickness 0.1524)
				)
				(justify mirror)
			)
		)
		(property "User Part Number" "PARTNUM*"
			(at -0.02032 4.024884 90)
			(unlocked yes)
			(layer "Cmts.User")
			(hide yes)
			(effects
				(font
					(size 0.7874 0.5842)
					(thickness 0.1524)
				)
				(justify mirror)
			)
		)
		(property "Device Type" "RESISTOR-G155-11001-01,1KOHM,1%"
			(at -0.008382 1.210564 90)
			(unlocked yes)
			(layer "B.Fab")
			(hide yes)
			(effects
				(font
					(size 0.7874 0.5842)
					(thickness 0.1524)
				)
				(justify mirror)
			)
		)
		(duplicate_pad_numbers_are_jumpers no)
		(fp_line
			(start 1.143 -0.5588)
			(end 1.143 0.5588)
			(stroke
				(width 0.1)
				(type default)
			)
			(layer "B.SilkS")
		)
		(fp_line
			(start -1.143 -0.5588)
			(end 1.143 -0.5588)
			(stroke
				(width 0.1)
				(type default)
			)
			(layer "B.SilkS")
		)
		(fp_line
			(start 1.143 0.5588)
			(end -1.143 0.5588)
			(stroke
				(width 0.1)
				(type default)
			)
			(layer "B.SilkS")
		)
		(fp_line
			(start -1.143 0.5588)
			(end -1.143 -0.5588)
			(stroke
				(width 0.1)
				(type default)
			)
			(layer "B.SilkS")
		)
		(fp_rect
			(start 1.143 0.5588)
			(end -1.143 -0.5588)
			(stroke
				(width 0)
				(type default)
			)
			(fill no)
			(layer "B.CrtYd")
		)
		(fp_line
			(start 0.508 -0.3048)
			(end 0.508 0.3048)
			(stroke
				(width 0.1)
				(type default)
			)
			(layer "B.Fab")
		)
		(fp_line
			(start -0.508 -0.3048)
			(end 0.508 -0.3048)
			(stroke
				(width 0.1)
				(type default)
			)
			(layer "B.Fab")
		)
		(fp_line
			(start 0.508 0.3048)
			(end -0.508 0.3048)
			(stroke
				(width 0.1)
				(type default)
			)
			(layer "B.Fab")
		)
		(fp_line
			(start -0.508 0.3048)
			(end -0.508 -0.3048)
			(stroke
				(width 0.1)
				(type default)
			)
			(layer "B.Fab")
		)
		(pad "1" smd rect
			(at 0.5334 0 270)
			(size 0.7112 0.6096)
			(layers "B.Cu" "B.Mask" "B.Paste")
			(net "XP5R0V_USB_CONN")
		)
		(pad "2" smd rect
			(at -0.5334 0 270)
			(size 0.7112 0.6096)
			(layers "B.Cu" "B.Mask" "B.Paste")
			(net "XP5R0V_USB_CONN_DET")
		)
		(zone
			(layer "B.Cu")
			(hatch none 0.5)
			(connect_pads
				(clearance 0)
			)
			(min_thickness 0.25)
			(keepout
				(tracks allowed)
				(vias not_allowed)
				(pads allowed)
				(copperpour not_allowed)
				(footprints allowed)
			)
			(placement
				(enabled no)
				(sheetname "")
			)
			(fill
				(thermal_gap 0.5)
				(thermal_bridge_width 0.5)
				(island_removal_mode 0)
			)
			(polygon
				(pts
					(xy 160.3248 -50.590196) (xy 159.7152 -50.590196) (xy 159.7152 -50.437796) (xy 160.3248 -50.437796)
				)
			)
		)
	)
)
